(kicad_pcb
	(version 20260206)
	(generator "pcbnew")
	(generator_version "10.0")
	(general
		(thickness 1.6)
		(legacy_teardrops no)
	)
	(paper "A4")
	(title_block
		(title "Bryce Canyon_SCC_16316-1_OCP.brd")
		(comment 1 "Bryce Canyon / footprints 696-703 of 1561")
	)
	(layers
		(0 "F.Cu" signal "TOP")
		(4 "In1.Cu" signal "L2GND")
		(6 "In2.Cu" signal "L3")
		(8 "In3.Cu" signal "L4VCC")
		(10 "In4.Cu" signal "L5VCC")
		(12 "In5.Cu" signal "L6")
		(14 "In6.Cu" signal "L7GND")
		(2 "B.Cu" signal "BOTTOM")
		(9 "F.Adhes" user "F.Adhesive")
		(11 "B.Adhes" user "B.Adhesive")
		(13 "F.Paste" user "Package Geometry/Pastemask Top")
		(15 "B.Paste" user "Package Geometry/Pastemask Bottom")
		(5 "F.SilkS" user "Ref Des/Silkscreen Top")
		(7 "B.SilkS" user "Ref Des/Silkscreen Bottom")
		(1 "F.Mask" user "Board Geometry/Soldermask Top")
		(3 "B.Mask" user "Board Geometry/Soldermask Bottom")
		(17 "Dwgs.User" user "User.Drawings")
		(19 "Cmts.User" user "User.Comments")
		(21 "Eco1.User" user "User.Eco1")
		(23 "Eco2.User" user "User.Eco2")
		(25 "Edge.Cuts" user "Board Geometry/Outline")
		(27 "Margin" user)
		(31 "F.CrtYd" user "Package Geometry/Place Bound Top")
		(29 "B.CrtYd" user "Package Geometry/Place Bound Bottom")
		(35 "F.Fab" user "Ref Des/Assembly Top")
		(33 "B.Fab" user "Ref Des/Assembly Bottom")
	)
	(footprint ""
		(layer "F.Cu")
		(at 192.951354 -67.337178 180)
		(property "Reference" "R297"
			(at 0 0 180)
			(layer "F.SilkS")
			(hide yes)
			(effects
				(font
					(size 1.27 1.27)
				)
			)
		)
		(property "Value" "0R2J-2-GP"
			(at 0.064008 -3.993896 180)
			(unlocked yes)
			(layer "F.Fab")
			(hide yes)
			(effects
				(font
					(size 1.016 1.016)
					(thickness 0.1524)
				)
			)
		)
		(property "Device Type" "R402H16"
			(at 0.064008 -5.517896 180)
			(unlocked yes)
			(layer "F.Fab")
			(hide yes)
			(effects
				(font
					(size 1.016 1.016)
					(thickness 0.1524)
				)
			)
		)
		(duplicate_pad_numbers_are_jumpers no)
		(fp_line
			(start 0.508 -0.9398)
			(end -0.508 -0.9398)
			(stroke
				(width 0.1524)
				(type default)
			)
			(layer "F.SilkS")
		)
		(fp_line
			(start -0.508 -0.9398)
			(end -0.508 0.9398)
			(stroke
				(width 0.1524)
				(type default)
			)
			(layer "F.SilkS")
		)
		(fp_rect
			(start -0.508 0.9398)
			(end 0.508 -0.9398)
			(stroke
				(width 0)
				(type default)
			)
			(fill no)
			(layer "F.CrtYd")
		)
		(fp_rect
			(start -0.508 0.9398)
			(end 0.508 -0.9398)
			(stroke
				(width 0)
				(type default)
			)
			(fill no)
			(layer "F.Fab")
		)
		(pad "1" smd custom
			(at 0 -0.4445 180)
			(size 0.1397 0.1397)
			(layers "F.Cu" "F.Mask" "F.Paste")
			(net "UART_IOC_TX")
			(options
				(clearance outline)
				(anchor circle)
			)
			(primitives
				(gr_poly
					(pts
						(arc
							(start -0.1778 -0.2794)
							(mid -0.249642 -0.249642)
							(end -0.2794 -0.1778)
						)
						(arc
							(start -0.2794 0.1778)
							(mid -0.249642 0.249642)
							(end -0.1778 0.2794)
						)
						(arc
							(start 0.1778 0.2794)
							(mid 0.249642 0.249642)
							(end 0.2794 0.1778)
						)
						(arc
							(start 0.2794 -0.1778)
							(mid 0.249642 -0.249642)
							(end 0.1778 -0.2794)
						)
					)
					(width 0)
					(fill yes)
				)
			)
		)
		(pad "2" smd custom
			(at 0 0.4445 180)
			(size 0.1397 0.1397)
			(layers "F.Cu" "F.Mask" "F.Paste")
			(net "IOC_UART_R_TX")
			(options
				(clearance outline)
				(anchor circle)
			)
			(primitives
				(gr_poly
					(pts
						(arc
							(start -0.1778 -0.2794)
							(mid -0.249642 -0.249642)
							(end -0.2794 -0.1778)
						)
						(arc
							(start -0.2794 0.1778)
							(mid -0.249642 0.249642)
							(end -0.1778 0.2794)
						)
						(arc
							(start 0.1778 0.2794)
							(mid 0.249642 0.249642)
							(end 0.2794 0.1778)
						)
						(arc
							(start 0.2794 -0.1778)
							(mid 0.249642 -0.249642)
							(end 0.1778 -0.2794)
						)
					)
					(width 0)
					(fill yes)
				)
			)
		)
	)
	(footprint ""
		(layer "F.Cu")
		(at 51.308 -75.8952 90)
		(property "Reference" "R471"
			(at 0 0 90)
			(layer "F.SilkS")
			(hide yes)
			(effects
				(font
					(size 1.27 1.27)
				)
			)
		)
		(property "Value" "1KR2F-3-GP"
			(at 0.064008 -3.993896 90)
			(unlocked yes)
			(layer "F.Fab")
			(hide yes)
			(effects
				(font
					(size 1.016 1.016)
					(thickness 0.1524)
				)
			)
		)
		(property "Device Type" "R402H16"
			(at 0.064008 -5.517896 90)
			(unlocked yes)
			(layer "F.Fab")
			(hide yes)
			(effects
				(font
					(size 1.016 1.016)
					(thickness 0.1524)
				)
			)
		)
		(duplicate_pad_numbers_are_jumpers no)
		(fp_line
			(start 0.508 -0.9398)
			(end -0.508 -0.9398)
			(stroke
				(width 0.1524)
				(type default)
			)
			(layer "F.SilkS")
		)
		(fp_line
			(start -0.508 -0.9398)
			(end -0.508 0.9398)
			(stroke
				(width 0.1524)
				(type default)
			)
			(layer "F.SilkS")
		)
		(fp_rect
			(start -0.508 0.9398)
			(end 0.508 -0.9398)
			(stroke
				(width 0)
				(type default)
			)
			(fill no)
			(layer "F.CrtYd")
		)
		(fp_rect
			(start -0.508 0.9398)
			(end 0.508 -0.9398)
			(stroke
				(width 0)
				(type default)
			)
			(fill no)
			(layer "F.Fab")
		)
		(pad "1" smd custom
			(at 0 -0.4445 90)
			(size 0.1397 0.1397)
			(layers "F.Cu" "F.Mask" "F.Paste")
			(net "P3V3")
			(options
				(clearance outline)
				(anchor circle)
			)
			(primitives
				(gr_poly
					(pts
						(arc
							(start -0.1778 -0.2794)
							(mid -0.249642 -0.249642)
							(end -0.2794 -0.1778)
						)
						(arc
							(start -0.2794 0.1778)
							(mid -0.249642 0.249642)
							(end -0.1778 0.2794)
						)
						(arc
							(start 0.1778 0.2794)
							(mid 0.249642 0.249642)
							(end 0.2794 0.1778)
						)
						(arc
							(start 0.2794 -0.1778)
							(mid 0.249642 -0.249642)
							(end 0.1778 -0.2794)
						)
					)
					(width 0)
					(fill yes)
				)
			)
		)
		(pad "2" smd custom
			(at 0 0.4445 90)
			(size 0.1397 0.1397)
			(layers "F.Cu" "F.Mask" "F.Paste")
			(net "I2C_CLIP_SDA7")
			(options
				(clearance outline)
				(anchor circle)
			)
			(primitives
				(gr_poly
					(pts
						(arc
							(start -0.1778 -0.2794)
							(mid -0.249642 -0.249642)
							(end -0.2794 -0.1778)
						)
						(arc
							(start -0.2794 0.1778)
							(mid -0.249642 0.249642)
							(end -0.1778 0.2794)
						)
						(arc
							(start 0.1778 0.2794)
							(mid 0.249642 0.249642)
							(end 0.2794 0.1778)
						)
						(arc
							(start 0.2794 -0.1778)
							(mid 0.249642 -0.249642)
							(end 0.1778 -0.2794)
						)
					)
					(width 0)
					(fill yes)
				)
			)
		)
	)
	(footprint ""
		(layer "F.Cu")
		(at 158.496 -41.275 90)
		(property "Reference" "R177"
			(at 0 0 90)
			(layer "F.SilkS")
			(hide yes)
			(effects
				(font
					(size 1.27 1.27)
				)
			)
		)
		(property "Value" "0R2J-2-GP"
			(at 0.064008 -3.993896 90)
			(unlocked yes)
			(layer "F.Fab")
			(hide yes)
			(effects
				(font
					(size 1.016 1.016)
					(thickness 0.1524)
				)
			)
		)
		(property "Device Type" "R402H16"
			(at 0.064008 -5.517896 90)
			(unlocked yes)
			(layer "F.Fab")
			(hide yes)
			(effects
				(font
					(size 1.016 1.016)
					(thickness 0.1524)
				)
			)
		)
		(duplicate_pad_numbers_are_jumpers no)
		(fp_line
			(start 0.508 -0.9398)
			(end -0.508 -0.9398)
			(stroke
				(width 0.1524)
				(type default)
			)
			(layer "F.SilkS")
		)
		(fp_line
			(start -0.508 -0.9398)
			(end -0.508 0.9398)
			(stroke
				(width 0.1524)
				(type default)
			)
			(layer "F.SilkS")
		)
		(fp_rect
			(start -0.508 0.9398)
			(end 0.508 -0.9398)
			(stroke
				(width 0)
				(type default)
			)
			(fill no)
			(layer "F.CrtYd")
		)
		(fp_rect
			(start -0.508 0.9398)
			(end 0.508 -0.9398)
			(stroke
				(width 0)
				(type default)
			)
			(fill no)
			(layer "F.Fab")
		)
		(pad "1" smd custom
			(at 0 -0.4445 90)
			(size 0.1397 0.1397)
			(layers "F.Cu" "F.Mask" "F.Paste")
			(net "REF_CLK")
			(options
				(clearance outline)
				(anchor circle)
			)
			(primitives
				(gr_poly
					(pts
						(arc
							(start -0.1778 -0.2794)
							(mid -0.249642 -0.249642)
							(end -0.2794 -0.1778)
						)
						(arc
							(start -0.2794 0.1778)
							(mid -0.249642 0.249642)
							(end -0.1778 0.2794)
						)
						(arc
							(start 0.1778 0.2794)
							(mid 0.249642 0.249642)
							(end 0.2794 0.1778)
						)
						(arc
							(start 0.2794 -0.1778)
							(mid 0.249642 -0.249642)
							(end 0.1778 -0.2794)
						)
					)
					(width 0)
					(fill yes)
				)
			)
		)
		(pad "2" smd custom
			(at 0 0.4445 90)
			(size 0.1397 0.1397)
			(layers "F.Cu" "F.Mask" "F.Paste")
			(net "IOC_REF_CLK_N")
			(options
				(clearance outline)
				(anchor circle)
			)
			(primitives
				(gr_poly
					(pts
						(arc
							(start -0.1778 -0.2794)
							(mid -0.249642 -0.249642)
							(end -0.2794 -0.1778)
						)
						(arc
							(start -0.2794 0.1778)
							(mid -0.249642 0.249642)
							(end -0.1778 0.2794)
						)
						(arc
							(start 0.1778 0.2794)
							(mid 0.249642 0.249642)
							(end 0.2794 0.1778)
						)
						(arc
							(start 0.2794 -0.1778)
							(mid 0.249642 -0.249642)
							(end 0.1778 -0.2794)
						)
					)
					(width 0)
					(fill yes)
				)
			)
		)
	)
	(footprint ""
		(layer "F.Cu")
		(at 148.509736 -44.828714 102)
		(property "Reference" "C337"
			(at 0 0 102)
			(layer "F.SilkS")
			(hide yes)
			(effects
				(font
					(size 1.27 1.27)
				)
			)
		)
		(property "Value" "SCD01U16V1KX-GP"
			(at -2.832048 -1.739777 102)
			(unlocked yes)
			(layer "F.Fab")
			(hide yes)
			(effects
				(font
					(size 1.016 1.016)
					(thickness 0.1524)
				)
			)
		)
		(property "Device Type" "C0201H13"
			(at -2.832174 -3.263834 102)
			(unlocked yes)
			(layer "F.Fab")
			(hide yes)
			(effects
				(font
					(size 1.016 1.016)
					(thickness 0.1524)
				)
			)
		)
		(duplicate_pad_numbers_are_jumpers no)
		(fp_poly
			(pts
				(xy -0.279454 -0.647706) (xy 0.279346 -0.647706) (xy 0.279346 0.647694) (xy -0.279454 0.647694)
			)
			(stroke
				(width 0)
				(type default)
			)
			(fill no)
			(layer "F.CrtYd")
		)
		(fp_poly
			(pts
				(xy -0.279454 -0.647706) (xy 0.279346 -0.647706) (xy 0.279346 0.647694) (xy -0.279454 0.647694)
			)
			(stroke
				(width 0)
				(type default)
			)
			(fill no)
			(layer "F.Fab")
		)
		(pad "1" smd custom
			(at -0.000001 -0.2794 102)
			(size 0.0762 0.0762)
			(layers "F.Cu" "F.Mask" "F.Paste")
			(net "PHY_SCC_TO_IOC_44_DP")
			(options
				(clearance outline)
				(anchor circle)
			)
			(primitives
				(gr_poly
					(pts
						(arc
							(start 0.1524 -0.127)
							(mid 0.137521 -0.162921)
							(end 0.1016 -0.1778)
						)
						(arc
							(start -0.1016 -0.1778)
							(mid -0.137521 -0.162921)
							(end -0.1524 -0.127)
						)
						(arc
							(start -0.1524 0.127)
							(mid -0.137521 0.162921)
							(end -0.1016 0.1778)
						)
						(arc
							(start 0.1016 0.1778)
							(mid 0.137521 0.162921)
							(end 0.1524 0.127)
						)
					)
					(width 0)
					(fill yes)
				)
			)
		)
		(pad "2" smd custom
			(at 0.000001 0.2794 102)
			(size 0.0762 0.0762)
			(layers "F.Cu" "F.Mask" "F.Paste")
			(net "PHY_SCC_TO_IOC_C_44_DP")
			(options
				(clearance outline)
				(anchor circle)
			)
			(primitives
				(gr_poly
					(pts
						(arc
							(start 0.1524 -0.127)
							(mid 0.137521 -0.162921)
							(end 0.1016 -0.1778)
						)
						(arc
							(start -0.1016 -0.1778)
							(mid -0.137521 -0.162921)
							(end -0.1524 -0.127)
						)
						(arc
							(start -0.1524 0.127)
							(mid -0.137521 0.162921)
							(end -0.1016 0.1778)
						)
						(arc
							(start 0.1016 0.1778)
							(mid 0.137521 0.162921)
							(end 0.1524 0.127)
						)
					)
					(width 0)
					(fill yes)
				)
			)
		)
	)
	(footprint ""
		(layer "F.Cu")
		(at 160.274 -76.934314 90)
		(property "Reference" "C520"
			(at 0 0 90)
			(layer "F.SilkS")
			(hide yes)
			(effects
				(font
					(size 1.27 1.27)
				)
			)
		)
		(property "Value" "SC1U16V2KX-7-GP"
			(at 1.7526 -1.6002 90)
			(unlocked yes)
			(layer "F.Fab")
			(hide yes)
			(effects
				(font
					(size 1.016 1.016)
					(thickness 0.1524)
				)
			)
		)
		(property "Device Type" "C402-TO0D2H24"
			(at 1.7526 -3.1242 90)
			(unlocked yes)
			(layer "F.Fab")
			(hide yes)
			(effects
				(font
					(size 1.016 1.016)
					(thickness 0.1524)
				)
			)
		)
		(duplicate_pad_numbers_are_jumpers no)
		(fp_rect
			(start -0.4826 0.889)
			(end 0.4826 -0.889)
			(stroke
				(width 0)
				(type default)
			)
			(fill no)
			(layer "F.CrtYd")
		)
		(fp_rect
			(start -0.4826 0.889)
			(end 0.4826 -0.889)
			(stroke
				(width 0)
				(type default)
			)
			(fill no)
			(layer "F.Fab")
		)
		(pad "1" smd custom
			(at 0 -0.4572 90)
			(size 0.1524 0.1524)
			(layers "F.Cu" "F.Mask" "F.Paste")
			(net "P3V3")
			(options
				(clearance outline)
				(anchor circle)
			)
			(primitives
				(gr_poly
					(pts
						(arc
							(start -0.254 0.3048)
							(mid -0.325842 0.275042)
							(end -0.3556 0.2032)
						)
						(arc
							(start -0.3556 -0.2032)
							(mid -0.325842 -0.275042)
							(end -0.254 -0.3048)
						)
						(arc
							(start 0.254 -0.3048)
							(mid 0.325842 -0.275042)
							(end 0.3556 -0.2032)
						)
						(arc
							(start 0.3556 0.2032)
							(mid 0.325842 0.275042)
							(end 0.254 0.3048)
						)
					)
					(width 0)
					(fill yes)
				)
			)
		)
		(pad "2" smd custom
			(at 0 0.4572 90)
			(size 0.1524 0.1524)
			(layers "F.Cu" "F.Mask" "F.Paste")
			(net "GND")
			(options
				(clearance outline)
				(anchor circle)
			)
			(primitives
				(gr_poly
					(pts
						(arc
							(start -0.254 0.3048)
							(mid -0.325842 0.275042)
							(end -0.3556 0.2032)
						)
						(arc
							(start -0.3556 -0.2032)
							(mid -0.325842 -0.275042)
							(end -0.254 -0.3048)
						)
						(arc
							(start 0.254 -0.3048)
							(mid 0.325842 -0.275042)
							(end 0.3556 -0.2032)
						)
						(arc
							(start 0.3556 0.2032)
							(mid 0.325842 0.275042)
							(end 0.254 0.3048)
						)
					)
					(width 0)
					(fill yes)
				)
			)
		)
	)
	(footprint ""
		(layer "F.Cu")
		(at 184.413906 -21.57857)
		(property "Reference" "TP133"
			(at 0 0 0)
			(layer "F.SilkS")
			(hide yes)
			(effects
				(font
					(size 1.27 1.27)
				)
			)
		)
		(property "Value" "TPAD28-2-GP"
			(at -0.0127 -1.6637 0)
			(unlocked yes)
			(layer "F.Fab")
			(hide yes)
			(effects
				(font
					(size 1.016 1.016)
					(thickness 0.1524)
				)
			)
		)
		(property "Device Type" "TPAD28"
			(at -0.0127 -3.1877 0)
			(unlocked yes)
			(layer "F.Fab")
			(hide yes)
			(effects
				(font
					(size 1.016 1.016)
					(thickness 0.1524)
				)
			)
		)
		(duplicate_pad_numbers_are_jumpers no)
		(fp_poly
			(pts
				(arc
					(start 0.3556 0)
					(mid -0.3556 0)
					(end 0.3556 0)
				)
			)
			(stroke
				(width 0)
				(type default)
			)
			(fill no)
			(layer "F.CrtYd")
		)
		(fp_poly
			(pts
				(arc
					(start 0.6096 0)
					(mid -0.6096 0)
					(end 0.6096 0)
				)
			)
			(stroke
				(width 0)
				(type default)
			)
			(fill no)
			(layer "F.Fab")
		)
		(pad "1" smd circle
			(at 0 0)
			(size 0.7112 0.7112)
			(layers "F.Cu" "F.Mask" "F.Paste")
			(net "SYS_DBMODE1")
		)
	)
	(footprint ""
		(layer "F.Cu")
		(at 120.8786 -89.1032 90)
		(property "Reference" "R33"
			(at 0 0 90)
			(layer "F.SilkS")
			(hide yes)
			(effects
				(font
					(size 1.27 1.27)
				)
			)
		)
		(property "Value" "4K7R2F-GP"
			(at 0.064008 -3.993896 90)
			(unlocked yes)
			(layer "F.Fab")
			(hide yes)
			(effects
				(font
					(size 1.016 1.016)
					(thickness 0.1524)
				)
			)
		)
		(property "Device Type" "R402H16"
			(at 0.064008 -5.517896 90)
			(unlocked yes)
			(layer "F.Fab")
			(hide yes)
			(effects
				(font
					(size 1.016 1.016)
					(thickness 0.1524)
				)
			)
		)
		(duplicate_pad_numbers_are_jumpers no)
		(fp_line
			(start 0.508 -0.9398)
			(end -0.508 -0.9398)
			(stroke
				(width 0.1524)
				(type default)
			)
			(layer "F.SilkS")
		)
		(fp_line
			(start -0.508 -0.9398)
			(end -0.508 0.9398)
			(stroke
				(width 0.1524)
				(type default)
			)
			(layer "F.SilkS")
		)
		(fp_rect
			(start -0.508 0.9398)
			(end 0.508 -0.9398)
			(stroke
				(width 0)
				(type default)
			)
			(fill no)
			(layer "F.CrtYd")
		)
		(fp_rect
			(start -0.508 0.9398)
			(end 0.508 -0.9398)
			(stroke
				(width 0)
				(type default)
			)
			(fill no)
			(layer "F.Fab")
		)
		(pad "1" smd custom
			(at 0 -0.4445 90)
			(size 0.1397 0.1397)
			(layers "F.Cu" "F.Mask" "F.Paste")
			(net "P1V8_E")
			(options
				(clearance outline)
				(anchor circle)
			)
			(primitives
				(gr_poly
					(pts
						(arc
							(start -0.1778 -0.2794)
							(mid -0.249642 -0.249642)
							(end -0.2794 -0.1778)
						)
						(arc
							(start -0.2794 0.1778)
							(mid -0.249642 0.249642)
							(end -0.1778 0.2794)
						)
						(arc
							(start 0.1778 0.2794)
							(mid 0.249642 0.249642)
							(end 0.2794 0.1778)
						)
						(arc
							(start 0.2794 -0.1778)
							(mid 0.249642 -0.249642)
							(end 0.1778 -0.2794)
						)
					)
					(width 0)
					(fill yes)
				)
			)
		)
		(pad "2" smd custom
			(at 0 0.4445 90)
			(size 0.1397 0.1397)
			(layers "F.Cu" "F.Mask" "F.Paste")
			(net "EXP_GPIO13")
			(options
				(clearance outline)
				(anchor circle)
			)
			(primitives
				(gr_poly
					(pts
						(arc
							(start -0.1778 -0.2794)
							(mid -0.249642 -0.249642)
							(end -0.2794 -0.1778)
						)
						(arc
							(start -0.2794 0.1778)
							(mid -0.249642 0.249642)
							(end -0.1778 0.2794)
						)
						(arc
							(start 0.1778 0.2794)
							(mid 0.249642 0.249642)
							(end 0.2794 0.1778)
						)
						(arc
							(start 0.2794 -0.1778)
							(mid 0.249642 -0.249642)
							(end 0.1778 -0.2794)
						)
					)
					(width 0)
					(fill yes)
				)
			)
		)
	)
	(footprint ""
		(layer "F.Cu")
		(at 6.5278 -101.0158)
		(property "Reference" "R534"
			(at 0 0 0)
			(layer "F.SilkS")
			(hide yes)
			(effects
				(font
					(size 1.27 1.27)
				)
			)
		)
		(property "Value" "0R2J-2-GP"
			(at 0.064008 -3.993896 0)
			(unlocked yes)
			(layer "F.Fab")
			(hide yes)
			(effects
				(font
					(size 1.016 1.016)
					(thickness 0.1524)
				)
			)
		)
		(property "Device Type" "R402H16"
			(at 0.064008 -5.517896 0)
			(unlocked yes)
			(layer "F.Fab")
			(hide yes)
			(effects
				(font
					(size 1.016 1.016)
					(thickness 0.1524)
				)
			)
		)
		(duplicate_pad_numbers_are_jumpers no)
		(fp_line
			(start -0.508 -0.9398)
			(end -0.508 0.9398)
			(stroke
				(width 0.1524)
				(type default)
			)
			(layer "F.SilkS")
		)
		(fp_line
			(start 0.508 -0.9398)
			(end -0.508 -0.9398)
			(stroke
				(width 0.1524)
				(type default)
			)
			(layer "F.SilkS")
		)
		(fp_rect
			(start -0.508 0.9398)
			(end 0.508 -0.9398)
			(stroke
				(width 0)
				(type default)
			)
			(fill no)
			(layer "F.CrtYd")
		)
		(fp_rect
			(start -0.508 0.9398)
			(end 0.508 -0.9398)
			(stroke
				(width 0)
				(type default)
			)
			(fill no)
			(layer "F.Fab")
		)
		(pad "1" smd custom
			(at 0 -0.4445)
			(size 0.1397 0.1397)
			(layers "F.Cu" "F.Mask" "F.Paste")
			(net "SCC_FULL_PGOOD")
			(options
				(clearance outline)
				(anchor circle)
			)
			(primitives
				(gr_poly
					(pts
						(arc
							(start -0.1778 -0.2794)
							(mid -0.249642 -0.249642)
							(end -0.2794 -0.1778)
						)
						(arc
							(start -0.2794 0.1778)
							(mid -0.249642 0.249642)
							(end -0.1778 0.2794)
						)
						(arc
							(start 0.1778 0.2794)
							(mid 0.249642 0.249642)
							(end 0.2794 0.1778)
						)
						(arc
							(start 0.2794 -0.1778)
							(mid 0.249642 -0.249642)
							(end 0.1778 -0.2794)
						)
					)
					(width 0)
					(fill yes)
				)
			)
		)
		(pad "2" smd custom
			(at 0 0.4445)
			(size 0.1397 0.1397)
			(layers "F.Cu" "F.Mask" "F.Paste")
			(net "SCC_FULL_PGOOD_BUF_R")
			(options
				(clearance outline)
				(anchor circle)
			)
			(primitives
				(gr_poly
					(pts
						(arc
							(start -0.1778 -0.2794)
							(mid -0.249642 -0.249642)
							(end -0.2794 -0.1778)
						)
						(arc
							(start -0.2794 0.1778)
							(mid -0.249642 0.249642)
							(end -0.1778 0.2794)
						)
						(arc
							(start 0.1778 0.2794)
							(mid 0.249642 0.249642)
							(end 0.2794 0.1778)
						)
						(arc
							(start 0.2794 -0.1778)
							(mid 0.249642 -0.249642)
							(end 0.1778 -0.2794)
						)
					)
					(width 0)
					(fill yes)
				)
			)
		)
	)
)
